(kicad_pcb
	(version 20260206)
	(generator "pcbnew")
	(generator_version "10.0")
	(general
		(thickness 1.6)
		(legacy_teardrops no)
	)
	(paper "A4")
	(title_block
		(title "fcb — 12433-1M.1206WZS1330.brd")
		(comment 1 "Open Vault / Knox (Wiwynn) / footprint 261 of 495 (CN9), pads 1-56 of 56")
	)
	(layers
		(0 "F.Cu" signal "TOP")
		(4 "In1.Cu" signal "L2GND")
		(6 "In2.Cu" signal "L3VCC")
		(2 "B.Cu" signal "BOTTOM")
		(9 "F.Adhes" user "F.Adhesive")
		(11 "B.Adhes" user "B.Adhesive")
		(13 "F.Paste" user "Package Geometry/Pastemask Top")
		(15 "B.Paste" user "Package Geometry/Pastemask Bottom")
		(5 "F.SilkS" user "Ref Des/Silkscreen Top")
		(7 "B.SilkS" user "Ref Des/Silkscreen Bottom")
		(1 "F.Mask" user "Board Geometry/Soldermask Top")
		(3 "B.Mask" user "Board Geometry/Soldermask Bottom")
		(17 "Dwgs.User" user "User.Drawings")
		(19 "Cmts.User" user "User.Comments")
		(21 "Eco1.User" user "User.Eco1")
		(23 "Eco2.User" user "User.Eco2")
		(25 "Edge.Cuts" user "Board Geometry/Outline")
		(27 "Margin" user)
		(31 "F.CrtYd" user "Package Geometry/Place Bound Top")
		(29 "B.CrtYd" user "Package Geometry/Place Bound Bottom")
		(35 "F.Fab" user "Ref Des/Assembly Top")
		(33 "B.Fab" user "Ref Des/Assembly Bottom")
	)
	(footprint ""
		(layer "F.Cu")
		(at 20.500086 -56.999886 -90)
		(property "Reference" "CN9"
			(at 0 0 270)
			(layer "F.SilkS")
			(hide yes)
			(effects
				(font
					(size 1.27 1.27)
				)
			)
		)
		(property "Value" "FCI-CONN52-4R-1-GP"
			(at -30.89656 -6.096 270)
			(unlocked yes)
			(layer "F.Fab")
			(hide yes)
			(effects
				(font
					(size 1.016 1.016)
					(thickness 0.1524)
				)
			)
		)
		(property "Device Type" "51952-220LF"
			(at -30.89656 -7.62 270)
			(unlocked yes)
			(layer "F.Fab")
			(hide yes)
			(effects
				(font
					(size 1.016 1.016)
					(thickness 0.1524)
				)
			)
		)
		(duplicate_pad_numbers_are_jumpers no)
		(pad "" np_thru_hole circle
			(at -26.67 0 270)
			(size 0.254 0.254)
			(drill 3.2004)
			(layers "*.Cu" "*.Mask")
			(clearance 1.8288)
			(thermal_gap 1.8288)
		)
		(pad "" np_thru_hole circle
			(at -21.59 0 270)
			(size 0.254 0.254)
			(drill 2.5146)
			(layers "*.Cu" "*.Mask")
			(clearance 1.4859)
			(thermal_gap 1.4859)
		)
		(pad "" np_thru_hole circle
			(at 21.59 0 270)
			(size 0.254 0.254)
			(drill 2.5146)
			(layers "*.Cu" "*.Mask")
			(clearance 1.4859)
			(thermal_gap 1.4859)
		)
		(pad "" np_thru_hole circle
			(at 26.67 0 270)
			(size 0.254 0.254)
			(drill 3.2004)
			(layers "*.Cu" "*.Mask")
			(clearance 1.8288)
			(thermal_gap 1.8288)
		)
		(pad "A1" thru_hole circle
			(at -5.08 0 270)
			(size 1.4478 1.4478)
			(drill 1.0414)
			(layers "*.Cu" "*.Mask")
			(remove_unused_layers no)
			(net "I2C_C_SDA_CONN_R")
			(clearance 0.1524)
			(thermal_gap 0.1524)
		)
		(pad "A2" thru_hole circle
			(at -2.54 0 270)
			(size 1.4478 1.4478)
			(drill 1.0414)
			(layers "*.Cu" "*.Mask")
			(remove_unused_layers no)
			(net "GND")
			(clearance 0.1524)
			(thermal_gap 0.1524)
		)
		(pad "A3" thru_hole circle
			(at 0 0 270)
			(size 1.4478 1.4478)
			(drill 1.0414)
			(layers "*.Cu" "*.Mask")
			(remove_unused_layers no)
			(net "I2C_C_SCL_CONN_R")
			(clearance 0.1524)
			(thermal_gap 0.1524)
		)
		(pad "A4" thru_hole circle
			(at 2.54 0 270)
			(size 1.4478 1.4478)
			(drill 1.0414)
			(layers "*.Cu" "*.Mask")
			(remove_unused_layers no)
			(net "GND")
			(clearance 0.1524)
			(thermal_gap 0.1524)
		)
		(pad "A5" thru_hole circle
			(at 5.08 0 270)
			(size 1.4478 1.4478)
			(drill 1.0414)
			(layers "*.Cu" "*.Mask")
			(remove_unused_layers no)
			(net "PWM_EXP_1B")
			(clearance 0.1524)
			(thermal_gap 0.1524)
		)
		(pad "B1" thru_hole circle
			(at -5.08 -2.54 270)
			(size 1.4478 1.4478)
			(drill 1.0414)
			(layers "*.Cu" "*.Mask")
			(remove_unused_layers no)
			(net "GND")
			(clearance 0.1524)
			(thermal_gap 0.1524)
		)
		(pad "B2" thru_hole circle
			(at -2.54 -2.54 270)
			(size 1.4478 1.4478)
			(drill 1.0414)
			(layers "*.Cu" "*.Mask")
			(remove_unused_layers no)
			(net "PWM_EXP_1A")
			(clearance 0.1524)
			(thermal_gap 0.1524)
		)
		(pad "B3" thru_hole circle
			(at 0 -2.54 270)
			(size 1.4478 1.4478)
			(drill 1.0414)
			(layers "*.Cu" "*.Mask")
			(remove_unused_layers no)
			(net "GND")
			(clearance 0.1524)
			(thermal_gap 0.1524)
		)
		(pad "B4" thru_hole circle
			(at 2.54 -2.54 270)
			(size 1.4478 1.4478)
			(drill 1.0414)
			(layers "*.Cu" "*.Mask")
			(remove_unused_layers no)
			(net "SELF_1B_HB")
			(clearance 0.1524)
			(thermal_gap 0.1524)
		)
		(pad "B5" thru_hole circle
			(at 5.08 -2.54 270)
			(size 1.4478 1.4478)
			(drill 1.0414)
			(layers "*.Cu" "*.Mask")
			(remove_unused_layers no)
			(net "GND")
			(clearance 0.1524)
			(thermal_gap 0.1524)
		)
		(pad "C1" thru_hole circle
			(at -5.08 -5.08 270)
			(size 1.4478 1.4478)
			(drill 1.0414)
			(layers "*.Cu" "*.Mask")
			(remove_unused_layers no)
			(net "P12VU_2490_EN_1")
			(clearance 0.1524)
			(thermal_gap 0.1524)
		)
		(pad "C2" thru_hole circle
			(at -2.54 -5.08 270)
			(size 1.4478 1.4478)
			(drill 1.0414)
			(layers "*.Cu" "*.Mask")
			(remove_unused_layers no)
			(net "P12VU_2490_EN_2")
			(clearance 0.1524)
			(thermal_gap 0.1524)
		)
		(pad "C3" thru_hole circle
			(at 0 -5.08 270)
			(size 1.4478 1.4478)
			(drill 1.0414)
			(layers "*.Cu" "*.Mask")
			(remove_unused_layers no)
			(net "SELF_1A_HB")
			(clearance 0.1524)
			(thermal_gap 0.1524)
		)
		(pad "C4" thru_hole circle
			(at 2.54 -5.08 270)
			(size 1.4478 1.4478)
			(drill 1.0414)
			(layers "*.Cu" "*.Mask")
			(remove_unused_layers no)
			(net "SEB_PEER_1A_HB")
			(clearance 0.1524)
			(thermal_gap 0.1524)
		)
		(pad "C5" thru_hole circle
			(at 5.08 -5.08 270)
			(size 1.4478 1.4478)
			(drill 1.0414)
			(layers "*.Cu" "*.Mask")
			(remove_unused_layers no)
			(net "SEB_PEER_1B_HB")
			(clearance 0.1524)
			(thermal_gap 0.1524)
		)
		(pad "D1" thru_hole circle
			(at -5.08 -7.62 270)
			(size 1.4478 1.4478)
			(drill 1.0414)
			(layers "*.Cu" "*.Mask")
			(remove_unused_layers no)
			(net "PEER_TRAY PRESENT_UPPER")
			(clearance 0.1524)
			(thermal_gap 0.1524)
		)
		(pad "D2" thru_hole circle
			(at -2.54 -7.62 270)
			(size 1.4478 1.4478)
			(drill 1.0414)
			(layers "*.Cu" "*.Mask")
			(remove_unused_layers no)
			(net "UPPER_TRAY_ID")
			(clearance 0.1524)
			(thermal_gap 0.1524)
		)
		(pad "D3" thru_hole circle
			(at 0 -7.62 270)
			(size 1.4478 1.4478)
			(drill 1.0414)
			(layers "*.Cu" "*.Mask")
			(remove_unused_layers no)
			(net "FCB_HW_REVISION")
			(clearance 0.1524)
			(thermal_gap 0.1524)
		)
		(pad "D4" thru_hole circle
			(at 2.54 -7.62 270)
			(size 1.4478 1.4478)
			(drill 1.0414)
			(layers "*.Cu" "*.Mask")
			(remove_unused_layers no)
			(net "SD_LATCH_RELEASE_U")
			(clearance 0.1524)
			(thermal_gap 0.1524)
		)
		(pad "D5" thru_hole circle
			(at 5.08 -7.62 270)
			(size 1.4478 1.4478)
			(drill 1.0414)
			(layers "*.Cu" "*.Mask")
			(remove_unused_layers no)
			(net "SELF_TRAY_PRESENT_UPPER")
			(clearance 0.1524)
			(thermal_gap 0.1524)
		)
		(pad "P1_1" thru_hole circle
			(at -15.88008 0 270)
			(size 1.4478 1.4478)
			(drill 1.0414)
			(layers "*.Cu" "*.Mask")
			(remove_unused_layers no)
			(net "P12VU")
			(clearance 0.1524)
			(thermal_gap 0.1524)
		)
		(pad "P1_2" thru_hole circle
			(at -15.88008 -2.54 270)
			(size 1.4478 1.4478)
			(drill 1.0414)
			(layers "*.Cu" "*.Mask")
			(remove_unused_layers no)
			(net "P12VU")
			(clearance 0.1524)
			(thermal_gap 0.1524)
		)
		(pad "P1_3" thru_hole circle
			(at -15.88008 -5.08 270)
			(size 1.4478 1.4478)
			(drill 1.0414)
			(layers "*.Cu" "*.Mask")
			(remove_unused_layers no)
			(net "P12VU")
			(clearance 0.1524)
			(thermal_gap 0.1524)
		)
		(pad "P1_4" thru_hole circle
			(at -15.88008 -7.62 270)
			(size 1.4478 1.4478)
			(drill 1.0414)
			(layers "*.Cu" "*.Mask")
			(remove_unused_layers no)
			(net "P12VU")
			(clearance 0.1524)
			(thermal_gap 0.1524)
		)
		(pad "P1_5" thru_hole circle
			(at -13.34008 0 270)
			(size 1.4478 1.4478)
			(drill 1.0414)
			(layers "*.Cu" "*.Mask")
			(remove_unused_layers no)
			(net "P12VU")
			(clearance 0.1524)
			(thermal_gap 0.1524)
		)
		(pad "P1_6" thru_hole circle
			(at -13.34008 -2.54 270)
			(size 1.4478 1.4478)
			(drill 1.0414)
			(layers "*.Cu" "*.Mask")
			(remove_unused_layers no)
			(net "P12VU")
			(clearance 0.1524)
			(thermal_gap 0.1524)
		)
		(pad "P1_7" thru_hole circle
			(at -13.34008 -5.08 270)
			(size 1.4478 1.4478)
			(drill 1.0414)
			(layers "*.Cu" "*.Mask")
			(remove_unused_layers no)
			(net "P12VU")
			(clearance 0.1524)
			(thermal_gap 0.1524)
		)
		(pad "P1_8" thru_hole circle
			(at -13.34008 -7.62 270)
			(size 1.4478 1.4478)
			(drill 1.0414)
			(layers "*.Cu" "*.Mask")
			(remove_unused_layers no)
			(net "P12VU")
			(clearance 0.1524)
			(thermal_gap 0.1524)
		)
		(pad "P2_1" thru_hole circle
			(at -10.80008 0 270)
			(size 1.4478 1.4478)
			(drill 1.0414)
			(layers "*.Cu" "*.Mask")
			(remove_unused_layers no)
			(net "P12VU")
			(clearance 0.1524)
			(thermal_gap 0.1524)
		)
		(pad "P2_2" thru_hole circle
			(at -10.80008 -2.54 270)
			(size 1.4478 1.4478)
			(drill 1.0414)
			(layers "*.Cu" "*.Mask")
			(remove_unused_layers no)
			(net "P12VU")
			(clearance 0.1524)
			(thermal_gap 0.1524)
		)
		(pad "P2_3" thru_hole circle
			(at -10.80008 -5.08 270)
			(size 1.4478 1.4478)
			(drill 1.0414)
			(layers "*.Cu" "*.Mask")
			(remove_unused_layers no)
			(net "P12VU")
			(clearance 0.1524)
			(thermal_gap 0.1524)
		)
		(pad "P2_4" thru_hole circle
			(at -10.80008 -7.62 270)
			(size 1.4478 1.4478)
			(drill 1.0414)
			(layers "*.Cu" "*.Mask")
			(remove_unused_layers no)
			(net "P12VU")
			(clearance 0.1524)
			(thermal_gap 0.1524)
		)
		(pad "P2_5" thru_hole circle
			(at -8.26008 0 270)
			(size 1.4478 1.4478)
			(drill 1.0414)
			(layers "*.Cu" "*.Mask")
			(remove_unused_layers no)
			(net "P12VU")
			(clearance 0.1524)
			(thermal_gap 0.1524)
		)
		(pad "P2_6" thru_hole circle
			(at -8.26008 -2.54 270)
			(size 1.4478 1.4478)
			(drill 1.0414)
			(layers "*.Cu" "*.Mask")
			(remove_unused_layers no)
			(net "P12VU")
			(clearance 0.1524)
			(thermal_gap 0.1524)
		)
		(pad "P2_7" thru_hole circle
			(at -8.26008 -5.08 270)
			(size 1.4478 1.4478)
			(drill 1.0414)
			(layers "*.Cu" "*.Mask")
			(remove_unused_layers no)
			(net "P12VU")
			(clearance 0.1524)
			(thermal_gap 0.1524)
		)
		(pad "P2_8" thru_hole circle
			(at -8.26008 -7.62 270)
			(size 1.4478 1.4478)
			(drill 1.0414)
			(layers "*.Cu" "*.Mask")
			(remove_unused_layers no)
			(net "P12VU")
			(clearance 0.1524)
			(thermal_gap 0.1524)
		)
		(pad "P3_1" thru_hole circle
			(at 8.26008 0 270)
			(size 1.4478 1.4478)
			(drill 1.0414)
			(layers "*.Cu" "*.Mask")
			(remove_unused_layers no)
			(net "GND")
			(clearance 0.1524)
			(thermal_gap 0.1524)
		)
		(pad "P3_2" thru_hole circle
			(at 8.26008 -2.54 270)
			(size 1.4478 1.4478)
			(drill 1.0414)
			(layers "*.Cu" "*.Mask")
			(remove_unused_layers no)
			(net "GND")
			(clearance 0.1524)
			(thermal_gap 0.1524)
		)
		(pad "P3_3" thru_hole circle
			(at 8.26008 -5.08 270)
			(size 1.4478 1.4478)
			(drill 1.0414)
			(layers "*.Cu" "*.Mask")
			(remove_unused_layers no)
			(net "GND")
			(clearance 0.1524)
			(thermal_gap 0.1524)
		)
		(pad "P3_4" thru_hole circle
			(at 8.26008 -7.62 270)
			(size 1.4478 1.4478)
			(drill 1.0414)
			(layers "*.Cu" "*.Mask")
			(remove_unused_layers no)
			(net "GND")
			(clearance 0.1524)
			(thermal_gap 0.1524)
		)
		(pad "P3_5" thru_hole circle
			(at 10.80008 0 270)
			(size 1.4478 1.4478)
			(drill 1.0414)
			(layers "*.Cu" "*.Mask")
			(remove_unused_layers no)
			(net "GND")
			(clearance 0.1524)
			(thermal_gap 0.1524)
		)
		(pad "P3_6" thru_hole circle
			(at 10.80008 -2.54 270)
			(size 1.4478 1.4478)
			(drill 1.0414)
			(layers "*.Cu" "*.Mask")
			(remove_unused_layers no)
			(net "GND")
			(clearance 0.1524)
			(thermal_gap 0.1524)
		)
		(pad "P3_7" thru_hole circle
			(at 10.80008 -5.08 270)
			(size 1.4478 1.4478)
			(drill 1.0414)
			(layers "*.Cu" "*.Mask")
			(remove_unused_layers no)
			(net "GND")
			(clearance 0.1524)
			(thermal_gap 0.1524)
		)
		(pad "P3_8" thru_hole circle
			(at 10.80008 -7.62 270)
			(size 1.4478 1.4478)
			(drill 1.0414)
			(layers "*.Cu" "*.Mask")
			(remove_unused_layers no)
			(net "GND")
			(clearance 0.1524)
			(thermal_gap 0.1524)
		)
		(pad "P4_1" thru_hole circle
			(at 13.34008 0 270)
			(size 1.4478 1.4478)
			(drill 1.0414)
			(layers "*.Cu" "*.Mask")
			(remove_unused_layers no)
			(net "GND")
			(clearance 0.1524)
			(thermal_gap 0.1524)
		)
		(pad "P4_2" thru_hole circle
			(at 13.34008 -2.54 270)
			(size 1.4478 1.4478)
			(drill 1.0414)
			(layers "*.Cu" "*.Mask")
			(remove_unused_layers no)
			(net "GND")
			(clearance 0.1524)
			(thermal_gap 0.1524)
		)
		(pad "P4_3" thru_hole circle
			(at 13.34008 -5.08 270)
			(size 1.4478 1.4478)
			(drill 1.0414)
			(layers "*.Cu" "*.Mask")
			(remove_unused_layers no)
			(net "GND")
			(clearance 0.1524)
			(thermal_gap 0.1524)
		)
		(pad "P4_4" thru_hole circle
			(at 13.34008 -7.62 270)
			(size 1.4478 1.4478)
			(drill 1.0414)
			(layers "*.Cu" "*.Mask")
			(remove_unused_layers no)
			(net "GND")
			(clearance 0.1524)
			(thermal_gap 0.1524)
		)
		(pad "P4_5" thru_hole circle
			(at 15.88008 0 270)
			(size 1.4478 1.4478)
			(drill 1.0414)
			(layers "*.Cu" "*.Mask")
			(remove_unused_layers no)
			(net "GND")
			(clearance 0.1524)
			(thermal_gap 0.1524)
		)
		(pad "P4_6" thru_hole circle
			(at 15.88008 -2.54 270)
			(size 1.4478 1.4478)
			(drill 1.0414)
			(layers "*.Cu" "*.Mask")
			(remove_unused_layers no)
			(net "GND")
			(clearance 0.1524)
			(thermal_gap 0.1524)
		)
		(pad "P4_7" thru_hole circle
			(at 15.88008 -5.08 270)
			(size 1.4478 1.4478)
			(drill 1.0414)
			(layers "*.Cu" "*.Mask")
			(remove_unused_layers no)
			(net "GND")
			(clearance 0.1524)
			(thermal_gap 0.1524)
		)
		(pad "P4_8" thru_hole circle
			(at 15.88008 -7.62 270)
			(size 1.4478 1.4478)
			(drill 1.0414)
			(layers "*.Cu" "*.Mask")
			(remove_unused_layers no)
			(net "GND")
			(clearance 0.1524)
			(thermal_gap 0.1524)
		)
	)
)
